(kicad_pcb
	(version 20260206)
	(generator "pcbnew")
	(generator_version "10.0")
	(general
		(thickness 1.6)
		(legacy_teardrops no)
	)
	(paper "A4")
	(title_block
		(title "01162023_DA0F0TEBIF0_F0T_Expander_BD_F_brd_V02_OCP.brd")
		(comment 1 "Grand Teton / footprints 2976-2982 of 9728")
	)
	(layers
		(0 "F.Cu" signal "TOP")
		(4 "In1.Cu" signal "GND")
		(6 "In2.Cu" signal "VCC")
		(8 "In3.Cu" signal "VCC1")
		(10 "In4.Cu" signal "GND1")
		(12 "In5.Cu" signal "IN1")
		(14 "In6.Cu" signal "GND2")
		(16 "In7.Cu" signal "IN2")
		(18 "In8.Cu" signal "GND3")
		(20 "In9.Cu" signal "IN3")
		(22 "In10.Cu" signal "GND4")
		(24 "In11.Cu" signal "IN4")
		(26 "In12.Cu" signal "GND5")
		(28 "In13.Cu" signal "IN5")
		(30 "In14.Cu" signal "GND6")
		(32 "In15.Cu" signal "IN6")
		(34 "In16.Cu" signal "GND7")
		(2 "B.Cu" signal "BOTTOM")
		(9 "F.Adhes" user "F.Adhesive")
		(11 "B.Adhes" user "B.Adhesive")
		(13 "F.Paste" user "Package Geometry/Pastemask Top")
		(15 "B.Paste" user "Package Geometry/Pastemask Bottom")
		(5 "F.SilkS" user "Ref Des/Silkscreen Top")
		(7 "B.SilkS" user "Ref Des/Silkscreen Bottom")
		(1 "F.Mask" user "Board Geometry/Soldermask Top")
		(3 "B.Mask" user "Board Geometry/Soldermask Bottom")
		(17 "Dwgs.User" user "User.Drawings")
		(19 "Cmts.User" user "User.Comments")
		(21 "Eco1.User" user "User.Eco1")
		(23 "Eco2.User" user "User.Eco2")
		(25 "Edge.Cuts" user "Board Geometry/Outline")
		(27 "Margin" user)
		(31 "F.CrtYd" user "Package Geometry/Place Bound Top")
		(29 "B.CrtYd" user "Package Geometry/Place Bound Bottom")
		(35 "F.Fab" user "Ref Des/Assembly Top")
		(33 "B.Fab" user "Ref Des/Assembly Bottom")
	)
	(footprint ""
		(layer "F.Cu")
		(at 243.564918 -316.176914)
		(property "Reference" "PC247"
			(at 0 0 0)
			(layer "F.SilkS")
			(hide yes)
			(effects
				(font
					(size 1.27 1.27)
				)
			)
		)
		(property "Value" ""
			(at 0 0 0)
			(layer "F.Fab")
			(effects
				(font
					(size 1.27 1.27)
				)
			)
		)
		(duplicate_pad_numbers_are_jumpers no)
		(fp_line
			(start -1.524 -0.762)
			(end 1.524 -0.762)
			(stroke
				(width 0.1524)
				(type default)
			)
			(layer "F.SilkS")
		)
		(fp_line
			(start -1.524 0.762)
			(end -1.524 -0.762)
			(stroke
				(width 0.1524)
				(type default)
			)
			(layer "F.SilkS")
		)
		(fp_line
			(start 1.524 -0.762)
			(end 1.524 0.762)
			(stroke
				(width 0.1524)
				(type default)
			)
			(layer "F.SilkS")
		)
		(fp_line
			(start 1.524 0.762)
			(end -1.524 0.762)
			(stroke
				(width 0.1524)
				(type default)
			)
			(layer "F.SilkS")
		)
		(fp_line
			(start -1.1049 -0.724916)
			(end -1.1049 0.724916)
			(stroke
				(width 0.1)
				(type default)
			)
			(layer "F.Fab")
		)
		(fp_line
			(start -1.1049 0.724916)
			(end 1.1049 0.724916)
			(stroke
				(width 0.1)
				(type default)
			)
			(layer "F.Fab")
		)
		(fp_line
			(start 1.1049 -0.724916)
			(end -1.1049 -0.724916)
			(stroke
				(width 0.1)
				(type default)
			)
			(layer "F.Fab")
		)
		(fp_line
			(start 1.1049 0.724916)
			(end 1.1049 -0.724916)
			(stroke
				(width 0.1)
				(type default)
			)
			(layer "F.Fab")
		)
		(pad "1" smd rect
			(at -0.889 0 180)
			(size 1.016 1.27)
			(layers "F.Cu" "F.Mask" "F.Paste")
			(net "SW_P12V_P1V25_PEX2_FLT")
		)
		(pad "2" smd rect
			(at 0.889 0 180)
			(size 1.016 1.27)
			(layers "F.Cu" "F.Mask" "F.Paste")
			(net "GND")
		)
	)
	(footprint ""
		(layer "F.Cu")
		(at 315.78931 -63.56223)
		(property "Reference" "Q207"
			(at 1.160018 -1.900174 0)
			(unlocked yes)
			(layer "F.SilkS")
			(effects
				(font
					(size 0.7874 0.5842)
					(thickness 0.1524)
				)
			)
		)
		(property "Value" ""
			(at 0 0 0)
			(layer "F.Fab")
			(effects
				(font
					(size 1.27 1.27)
				)
			)
		)
		(duplicate_pad_numbers_are_jumpers no)
		(fp_line
			(start -1.376172 -1.199896)
			(end -0.508 -1.199896)
			(stroke
				(width 0.1524)
				(type default)
			)
			(layer "F.SilkS")
		)
		(fp_line
			(start -1.376172 1.199896)
			(end -1.376172 -1.199896)
			(stroke
				(width 0.1524)
				(type default)
			)
			(layer "F.SilkS")
		)
		(fp_line
			(start -0.508 -1.199896)
			(end 0 -0.762)
			(stroke
				(width 0.1524)
				(type default)
			)
			(layer "F.SilkS")
		)
		(fp_line
			(start 0 -0.762)
			(end 0.508 -1.199896)
			(stroke
				(width 0.1524)
				(type default)
			)
			(layer "F.SilkS")
		)
		(fp_line
			(start 0.508 -1.199896)
			(end 1.376172 -1.199896)
			(stroke
				(width 0.1524)
				(type default)
			)
			(layer "F.SilkS")
		)
		(fp_line
			(start 1.376172 -1.199896)
			(end 1.376172 1.199896)
			(stroke
				(width 0.1524)
				(type default)
			)
			(layer "F.SilkS")
		)
		(fp_line
			(start 1.376172 1.199896)
			(end -1.376172 1.199896)
			(stroke
				(width 0.1524)
				(type default)
			)
			(layer "F.SilkS")
		)
		(fp_poly
			(pts
				(xy -0.994918 -1.301242) (xy -0.613918 -2.063242) (xy -1.375918 -2.063242)
			)
			(stroke
				(width 0)
				(type default)
			)
			(fill yes)
			(layer "F.SilkS")
		)
		(fp_line
			(start -0.674878 -1.100074)
			(end 0.674878 -1.100074)
			(stroke
				(width 0.1)
				(type default)
			)
			(layer "F.Fab")
		)
		(fp_line
			(start -0.674878 1.100074)
			(end -0.674878 -1.100074)
			(stroke
				(width 0.1)
				(type default)
			)
			(layer "F.Fab")
		)
		(fp_line
			(start 0.674878 -1.100074)
			(end 0.674878 1.100074)
			(stroke
				(width 0.1)
				(type default)
			)
			(layer "F.Fab")
		)
		(fp_line
			(start 0.674878 1.100074)
			(end -0.674878 1.100074)
			(stroke
				(width 0.1)
				(type default)
			)
			(layer "F.Fab")
		)
		(fp_poly
			(pts
				(xy -1.4605 -0.7493) (xy -2.2225 -1.1303) (xy -2.2225 -0.3683)
			)
			(stroke
				(width 0)
				(type default)
			)
			(fill yes)
			(layer "F.Fab")
		)
		(pad "1" smd rect
			(at -0.899922 -0.750062 270)
			(size 0.6096 0.6096)
			(layers "F.Cu" "F.Mask" "F.Paste")
			(net "GND")
		)
		(pad "2" smd rect
			(at -0.899922 0 270)
			(size 0.4064 0.6096)
			(layers "F.Cu" "F.Mask" "F.Paste")
			(net "P12V_SSD11_PG_G1")
		)
		(pad "3" smd rect
			(at -0.899922 0.750062 270)
			(size 0.6096 0.6096)
			(layers "F.Cu" "F.Mask" "F.Paste")
			(net "PWRGD_P12V_SSD11_D")
		)
		(pad "4" smd rect
			(at 0.899922 0.750062 270)
			(size 0.6096 0.6096)
			(layers "F.Cu" "F.Mask" "F.Paste")
			(net "GND")
		)
		(pad "5" smd rect
			(at 0.899922 0 270)
			(size 0.4064 0.6096)
			(layers "F.Cu" "F.Mask" "F.Paste")
			(net "P12V_SSD11_PG_G2")
		)
		(pad "6" smd rect
			(at 0.899922 -0.750062 270)
			(size 0.6096 0.6096)
			(layers "F.Cu" "F.Mask" "F.Paste")
			(net "P12V_SSD11_PG_G2")
		)
	)
	(footprint ""
		(layer "F.Cu")
		(at 248.094754 -280.583386 180)
		(property "Reference" "R797"
			(at 0 0 180)
			(layer "F.SilkS")
			(hide yes)
			(effects
				(font
					(size 1.27 1.27)
				)
			)
		)
		(property "Value" ""
			(at 0 0 180)
			(layer "F.Fab")
			(effects
				(font
					(size 1.27 1.27)
				)
			)
		)
		(duplicate_pad_numbers_are_jumpers no)
		(fp_line
			(start 0.7874 0.4064)
			(end -0.7874 0.4064)
			(stroke
				(width 0.1524)
				(type default)
			)
			(layer "F.SilkS")
		)
		(fp_line
			(start 0.7874 -0.4064)
			(end 0.7874 0.4064)
			(stroke
				(width 0.1524)
				(type default)
			)
			(layer "F.SilkS")
		)
		(fp_line
			(start -0.7874 0.4064)
			(end -0.7874 -0.4064)
			(stroke
				(width 0.1524)
				(type default)
			)
			(layer "F.SilkS")
		)
		(fp_line
			(start -0.7874 -0.4064)
			(end 0.7874 -0.4064)
			(stroke
				(width 0.1524)
				(type default)
			)
			(layer "F.SilkS")
		)
		(fp_line
			(start 0.67945 0.3048)
			(end 0.120396 0.3048)
			(stroke
				(width 0.1)
				(type default)
			)
			(layer "F.Fab")
		)
		(fp_line
			(start 0.67945 -0.3048)
			(end 0.67945 0.3048)
			(stroke
				(width 0.1)
				(type default)
			)
			(layer "F.Fab")
		)
		(fp_line
			(start 0.12065 -0.2794)
			(end 0.12065 -0.3048)
			(stroke
				(width 0.1)
				(type default)
			)
			(layer "F.Fab")
		)
		(fp_line
			(start 0.12065 -0.3048)
			(end 0.67945 -0.3048)
			(stroke
				(width 0.1)
				(type default)
			)
			(layer "F.Fab")
		)
		(fp_line
			(start 0.120396 0.3048)
			(end 0.120396 0.2794)
			(stroke
				(width 0.1)
				(type default)
			)
			(layer "F.Fab")
		)
		(fp_line
			(start 0.120396 0.2794)
			(end -0.12065 0.2794)
			(stroke
				(width 0.1)
				(type default)
			)
			(layer "F.Fab")
		)
		(fp_line
			(start -0.12065 0.3048)
			(end -0.67945 0.3048)
			(stroke
				(width 0.1)
				(type default)
			)
			(layer "F.Fab")
		)
		(fp_line
			(start -0.12065 0.2794)
			(end -0.12065 0.3048)
			(stroke
				(width 0.1)
				(type default)
			)
			(layer "F.Fab")
		)
		(fp_line
			(start -0.12065 -0.2794)
			(end 0.12065 -0.2794)
			(stroke
				(width 0.1)
				(type default)
			)
			(layer "F.Fab")
		)
		(fp_line
			(start -0.12065 -0.305054)
			(end -0.12065 -0.2794)
			(stroke
				(width 0.1)
				(type default)
			)
			(layer "F.Fab")
		)
		(fp_line
			(start -0.67945 0.3048)
			(end -0.67945 -0.305054)
			(stroke
				(width 0.1)
				(type default)
			)
			(layer "F.Fab")
		)
		(fp_line
			(start -0.67945 -0.305054)
			(end -0.12065 -0.305054)
			(stroke
				(width 0.1)
				(type default)
			)
			(layer "F.Fab")
		)
		(pad "1" smd circle
			(at -0.40005 0 180)
			(size 0 0)
			(layers "F.Cu" "F.Mask" "F.Paste")
			(net "SMB_BIC_I2C6_MUX_PEX_ADC_R_SCL")
		)
		(pad "2" smd circle
			(at 0.40005 0 180)
			(size 0 0)
			(layers "F.Cu" "F.Mask" "F.Paste")
			(net "SMB_PEX2_P1V25_ADC_SCL")
		)
	)
	(footprint ""
		(layer "F.Cu")
		(at 434.141372 -350.098614 90)
		(property "Reference" "C2463"
			(at 0 0 90)
			(layer "F.SilkS")
			(hide yes)
			(effects
				(font
					(size 1.27 1.27)
				)
			)
		)
		(property "Value" ""
			(at 0 0 90)
			(layer "F.Fab")
			(effects
				(font
					(size 1.27 1.27)
				)
			)
		)
		(duplicate_pad_numbers_are_jumpers no)
		(fp_line
			(start 0.299974 -0.150114)
			(end 0.299974 0.150114)
			(stroke
				(width 0.1)
				(type default)
			)
			(layer "F.Fab")
		)
		(fp_line
			(start -0.299974 -0.150114)
			(end 0.299974 -0.150114)
			(stroke
				(width 0.1)
				(type default)
			)
			(layer "F.Fab")
		)
		(fp_line
			(start 0.299974 0.150114)
			(end -0.299974 0.150114)
			(stroke
				(width 0.1)
				(type default)
			)
			(layer "F.Fab")
		)
		(fp_line
			(start -0.299974 0.150114)
			(end -0.299974 -0.150114)
			(stroke
				(width 0.1)
				(type default)
			)
			(layer "F.Fab")
		)
		(pad "1" smd rect
			(at -0.2667 0 90)
			(size 0.3048 0.381)
			(layers "F.Cu" "F.Mask" "F.Paste")
			(net "P5E_PEX3_STN4_TX_DP<67>")
		)
		(pad "2" smd rect
			(at 0.2667 0 90)
			(size 0.3048 0.381)
			(layers "F.Cu" "F.Mask" "F.Paste")
			(net "P5E_PEX3_STN4_TX_C_DP<67>")
		)
	)
	(footprint ""
		(layer "F.Cu")
		(at 451.977506 -277.291292 90)
		(property "Reference" "R804"
			(at 0 0 90)
			(layer "F.SilkS")
			(hide yes)
			(effects
				(font
					(size 1.27 1.27)
				)
			)
		)
		(property "Value" ""
			(at 0 0 90)
			(layer "F.Fab")
			(effects
				(font
					(size 1.27 1.27)
				)
			)
		)
		(duplicate_pad_numbers_are_jumpers no)
		(fp_line
			(start 3.937508 -1.8796)
			(end -3.937508 -1.8796)
			(stroke
				(width 0.1524)
				(type default)
			)
			(layer "F.SilkS")
		)
		(fp_line
			(start -3.937508 -1.8796)
			(end -3.937508 1.8796)
			(stroke
				(width 0.1524)
				(type default)
			)
			(layer "F.SilkS")
		)
		(fp_line
			(start 3.937508 1.8796)
			(end 3.937508 -1.8796)
			(stroke
				(width 0.1524)
				(type default)
			)
			(layer "F.SilkS")
		)
		(fp_line
			(start -3.937508 1.8796)
			(end 3.937508 1.8796)
			(stroke
				(width 0.1524)
				(type default)
			)
			(layer "F.SilkS")
		)
		(fp_line
			(start 3.275076 -1.674876)
			(end -3.275076 -1.674876)
			(stroke
				(width 0.1)
				(type default)
			)
			(layer "F.Fab")
		)
		(fp_line
			(start -3.275076 -1.674876)
			(end -3.275076 1.674876)
			(stroke
				(width 0.1)
				(type default)
			)
			(layer "F.Fab")
		)
		(fp_line
			(start 3.275076 1.674876)
			(end 3.275076 -1.674876)
			(stroke
				(width 0.1)
				(type default)
			)
			(layer "F.Fab")
		)
		(fp_line
			(start -3.275076 1.674876)
			(end 3.275076 1.674876)
			(stroke
				(width 0.1)
				(type default)
			)
			(layer "F.Fab")
		)
		(pad "1" smd rect
			(at -2.350008 0 90)
			(size 2.921 3.5052)
			(layers "F.Cu" "F.Mask" "F.Paste")
			(net "P1V25_PEX3")
		)
		(pad "2" smd rect
			(at 2.350008 0 90)
			(size 2.921 3.5052)
			(layers "F.Cu" "F.Mask" "F.Paste")
			(net "P1V25_PEX3_R")
		)
	)
	(footprint ""
		(layer "F.Cu")
		(at 270.83004 -366.767364 90)
		(property "Reference" "PR6614"
			(at 0 0 90)
			(layer "F.SilkS")
			(hide yes)
			(effects
				(font
					(size 1.27 1.27)
				)
			)
		)
		(property "Value" ""
			(at 0 0 90)
			(layer "F.Fab")
			(effects
				(font
					(size 1.27 1.27)
				)
			)
		)
		(duplicate_pad_numbers_are_jumpers no)
		(fp_line
			(start 0.7874 -0.4064)
			(end 0.7874 0.4064)
			(stroke
				(width 0.1524)
				(type default)
			)
			(layer "F.SilkS")
		)
		(fp_line
			(start -0.7874 -0.4064)
			(end 0.7874 -0.4064)
			(stroke
				(width 0.1524)
				(type default)
			)
			(layer "F.SilkS")
		)
		(fp_line
			(start 0.7874 0.4064)
			(end -0.7874 0.4064)
			(stroke
				(width 0.1524)
				(type default)
			)
			(layer "F.SilkS")
		)
		(fp_line
			(start -0.7874 0.4064)
			(end -0.7874 -0.4064)
			(stroke
				(width 0.1524)
				(type default)
			)
			(layer "F.SilkS")
		)
		(fp_line
			(start -0.12065 -0.305054)
			(end -0.12065 -0.2794)
			(stroke
				(width 0.1)
				(type default)
			)
			(layer "F.Fab")
		)
		(fp_line
			(start -0.67945 -0.305054)
			(end -0.12065 -0.305054)
			(stroke
				(width 0.1)
				(type default)
			)
			(layer "F.Fab")
		)
		(fp_line
			(start 0.67945 -0.3048)
			(end 0.67945 0.3048)
			(stroke
				(width 0.1)
				(type default)
			)
			(layer "F.Fab")
		)
		(fp_line
			(start 0.12065 -0.3048)
			(end 0.67945 -0.3048)
			(stroke
				(width 0.1)
				(type default)
			)
			(layer "F.Fab")
		)
		(fp_line
			(start 0.12065 -0.2794)
			(end 0.12065 -0.3048)
			(stroke
				(width 0.1)
				(type default)
			)
			(layer "F.Fab")
		)
		(fp_line
			(start -0.12065 -0.2794)
			(end 0.12065 -0.2794)
			(stroke
				(width 0.1)
				(type default)
			)
			(layer "F.Fab")
		)
		(fp_line
			(start 0.120396 0.2794)
			(end -0.12065 0.2794)
			(stroke
				(width 0.1)
				(type default)
			)
			(layer "F.Fab")
		)
		(fp_line
			(start -0.12065 0.2794)
			(end -0.12065 0.3048)
			(stroke
				(width 0.1)
				(type default)
			)
			(layer "F.Fab")
		)
		(fp_line
			(start 0.67945 0.3048)
			(end 0.120396 0.3048)
			(stroke
				(width 0.1)
				(type default)
			)
			(layer "F.Fab")
		)
		(fp_line
			(start 0.120396 0.3048)
			(end 0.120396 0.2794)
			(stroke
				(width 0.1)
				(type default)
			)
			(layer "F.Fab")
		)
		(fp_line
			(start -0.12065 0.3048)
			(end -0.67945 0.3048)
			(stroke
				(width 0.1)
				(type default)
			)
			(layer "F.Fab")
		)
		(fp_line
			(start -0.67945 0.3048)
			(end -0.67945 -0.305054)
			(stroke
				(width 0.1)
				(type default)
			)
			(layer "F.Fab")
		)
		(pad "1" smd circle
			(at -0.40005 0 90)
			(size 0 0)
			(layers "F.Cu" "F.Mask" "F.Paste")
			(net "LTC4282_TEMP_R_D+")
		)
		(pad "2" smd circle
			(at 0.40005 0 90)
			(size 0 0)
			(layers "F.Cu" "F.Mask" "F.Paste")
			(net "LTC4282_TEMP_D+")
		)
	)
	(footprint ""
		(layer "F.Cu")
		(at 396.209266 -87.214202 180)
		(property "Reference" "R1763"
			(at 0 0 180)
			(layer "F.SilkS")
			(hide yes)
			(effects
				(font
					(size 1.27 1.27)
				)
			)
		)
		(property "Value" ""
			(at 0 0 180)
			(layer "F.Fab")
			(effects
				(font
					(size 1.27 1.27)
				)
			)
		)
		(duplicate_pad_numbers_are_jumpers no)
		(fp_line
			(start 0.7874 0.4064)
			(end -0.7874 0.4064)
			(stroke
				(width 0.1524)
				(type default)
			)
			(layer "F.SilkS")
		)
		(fp_line
			(start 0.7874 -0.4064)
			(end 0.7874 0.4064)
			(stroke
				(width 0.1524)
				(type default)
			)
			(layer "F.SilkS")
		)
		(fp_line
			(start -0.7874 0.4064)
			(end -0.7874 -0.4064)
			(stroke
				(width 0.1524)
				(type default)
			)
			(layer "F.SilkS")
		)
		(fp_line
			(start -0.7874 -0.4064)
			(end 0.7874 -0.4064)
			(stroke
				(width 0.1524)
				(type default)
			)
			(layer "F.SilkS")
		)
		(fp_line
			(start 0.67945 0.3048)
			(end 0.120396 0.3048)
			(stroke
				(width 0.1)
				(type default)
			)
			(layer "F.Fab")
		)
		(fp_line
			(start 0.67945 -0.3048)
			(end 0.67945 0.3048)
			(stroke
				(width 0.1)
				(type default)
			)
			(layer "F.Fab")
		)
		(fp_line
			(start 0.12065 -0.2794)
			(end 0.12065 -0.3048)
			(stroke
				(width 0.1)
				(type default)
			)
			(layer "F.Fab")
		)
		(fp_line
			(start 0.12065 -0.3048)
			(end 0.67945 -0.3048)
			(stroke
				(width 0.1)
				(type default)
			)
			(layer "F.Fab")
		)
		(fp_line
			(start 0.120396 0.3048)
			(end 0.120396 0.2794)
			(stroke
				(width 0.1)
				(type default)
			)
			(layer "F.Fab")
		)
		(fp_line
			(start 0.120396 0.2794)
			(end -0.12065 0.2794)
			(stroke
				(width 0.1)
				(type default)
			)
			(layer "F.Fab")
		)
		(fp_line
			(start -0.12065 0.3048)
			(end -0.67945 0.3048)
			(stroke
				(width 0.1)
				(type default)
			)
			(layer "F.Fab")
		)
		(fp_line
			(start -0.12065 0.2794)
			(end -0.12065 0.3048)
			(stroke
				(width 0.1)
				(type default)
			)
			(layer "F.Fab")
		)
		(fp_line
			(start -0.12065 -0.2794)
			(end 0.12065 -0.2794)
			(stroke
				(width 0.1)
				(type default)
			)
			(layer "F.Fab")
		)
		(fp_line
			(start -0.12065 -0.305054)
			(end -0.12065 -0.2794)
			(stroke
				(width 0.1)
				(type default)
			)
			(layer "F.Fab")
		)
		(fp_line
			(start -0.67945 0.3048)
			(end -0.67945 -0.305054)
			(stroke
				(width 0.1)
				(type default)
			)
			(layer "F.Fab")
		)
		(fp_line
			(start -0.67945 -0.305054)
			(end -0.12065 -0.305054)
			(stroke
				(width 0.1)
				(type default)
			)
			(layer "F.Fab")
		)
		(pad "1" smd circle
			(at -0.40005 0 180)
			(size 0 0)
			(layers "F.Cu" "F.Mask" "F.Paste")
			(net "P3V3_AUX")
		)
		(pad "2" smd circle
			(at 0.40005 0 180)
			(size 0 0)
			(layers "F.Cu" "F.Mask" "F.Paste")
			(net "SMB_BIC_I2C6_MUX_FRU_R_SDA")
		)
	)
)
